(kicad_pcb
	(version 20260206)
	(generator "pcbnew")
	(generator_version "10.0")
	(general
		(thickness 1.6)
		(legacy_teardrops no)
	)
	(paper "A4")
	(title_block
		(title "01162023_DA0F0TEBIF0_F0T_Expander_BD_F_brd_V02_OCP.brd")
		(comment 1 "Grand Teton / footprints 5390-5394 of 9728")
	)
	(layers
		(0 "F.Cu" signal "TOP")
		(4 "In1.Cu" signal "GND")
		(6 "In2.Cu" signal "VCC")
		(8 "In3.Cu" signal "VCC1")
		(10 "In4.Cu" signal "GND1")
		(12 "In5.Cu" signal "IN1")
		(14 "In6.Cu" signal "GND2")
		(16 "In7.Cu" signal "IN2")
		(18 "In8.Cu" signal "GND3")
		(20 "In9.Cu" signal "IN3")
		(22 "In10.Cu" signal "GND4")
		(24 "In11.Cu" signal "IN4")
		(26 "In12.Cu" signal "GND5")
		(28 "In13.Cu" signal "IN5")
		(30 "In14.Cu" signal "GND6")
		(32 "In15.Cu" signal "IN6")
		(34 "In16.Cu" signal "GND7")
		(2 "B.Cu" signal "BOTTOM")
		(9 "F.Adhes" user "F.Adhesive")
		(11 "B.Adhes" user "B.Adhesive")
		(13 "F.Paste" user "Package Geometry/Pastemask Top")
		(15 "B.Paste" user "Package Geometry/Pastemask Bottom")
		(5 "F.SilkS" user "Ref Des/Silkscreen Top")
		(7 "B.SilkS" user "Ref Des/Silkscreen Bottom")
		(1 "F.Mask" user "Board Geometry/Soldermask Top")
		(3 "B.Mask" user "Board Geometry/Soldermask Bottom")
		(17 "Dwgs.User" user "User.Drawings")
		(19 "Cmts.User" user "User.Comments")
		(21 "Eco1.User" user "User.Eco1")
		(23 "Eco2.User" user "User.Eco2")
		(25 "Edge.Cuts" user "Board Geometry/Outline")
		(27 "Margin" user)
		(31 "F.CrtYd" user "Package Geometry/Place Bound Top")
		(29 "B.CrtYd" user "Package Geometry/Place Bound Bottom")
		(35 "F.Fab" user "Ref Des/Assembly Top")
		(33 "B.Fab" user "Ref Des/Assembly Bottom")
	)
	(footprint ""
		(layer "F.Cu")
		(at 409.600908 -182.325518 180)
		(property "Reference" "R6447"
			(at 0 0 180)
			(layer "F.SilkS")
			(hide yes)
			(effects
				(font
					(size 1.27 1.27)
				)
			)
		)
		(property "Value" ""
			(at 0 0 180)
			(layer "F.Fab")
			(effects
				(font
					(size 1.27 1.27)
				)
			)
		)
		(duplicate_pad_numbers_are_jumpers no)
		(fp_line
			(start 0.7874 0.4064)
			(end -0.7874 0.4064)
			(stroke
				(width 0.1524)
				(type default)
			)
			(layer "F.SilkS")
		)
		(fp_line
			(start 0.7874 -0.4064)
			(end 0.7874 0.4064)
			(stroke
				(width 0.1524)
				(type default)
			)
			(layer "F.SilkS")
		)
		(fp_line
			(start -0.7874 0.4064)
			(end -0.7874 -0.4064)
			(stroke
				(width 0.1524)
				(type default)
			)
			(layer "F.SilkS")
		)
		(fp_line
			(start -0.7874 -0.4064)
			(end 0.7874 -0.4064)
			(stroke
				(width 0.1524)
				(type default)
			)
			(layer "F.SilkS")
		)
		(fp_line
			(start 0.67945 0.3048)
			(end 0.120396 0.3048)
			(stroke
				(width 0.1)
				(type default)
			)
			(layer "F.Fab")
		)
		(fp_line
			(start 0.67945 -0.3048)
			(end 0.67945 0.3048)
			(stroke
				(width 0.1)
				(type default)
			)
			(layer "F.Fab")
		)
		(fp_line
			(start 0.12065 -0.2794)
			(end 0.12065 -0.3048)
			(stroke
				(width 0.1)
				(type default)
			)
			(layer "F.Fab")
		)
		(fp_line
			(start 0.12065 -0.3048)
			(end 0.67945 -0.3048)
			(stroke
				(width 0.1)
				(type default)
			)
			(layer "F.Fab")
		)
		(fp_line
			(start 0.120396 0.3048)
			(end 0.120396 0.2794)
			(stroke
				(width 0.1)
				(type default)
			)
			(layer "F.Fab")
		)
		(fp_line
			(start 0.120396 0.2794)
			(end -0.12065 0.2794)
			(stroke
				(width 0.1)
				(type default)
			)
			(layer "F.Fab")
		)
		(fp_line
			(start -0.12065 0.3048)
			(end -0.67945 0.3048)
			(stroke
				(width 0.1)
				(type default)
			)
			(layer "F.Fab")
		)
		(fp_line
			(start -0.12065 0.2794)
			(end -0.12065 0.3048)
			(stroke
				(width 0.1)
				(type default)
			)
			(layer "F.Fab")
		)
		(fp_line
			(start -0.12065 -0.2794)
			(end 0.12065 -0.2794)
			(stroke
				(width 0.1)
				(type default)
			)
			(layer "F.Fab")
		)
		(fp_line
			(start -0.12065 -0.305054)
			(end -0.12065 -0.2794)
			(stroke
				(width 0.1)
				(type default)
			)
			(layer "F.Fab")
		)
		(fp_line
			(start -0.67945 0.3048)
			(end -0.67945 -0.305054)
			(stroke
				(width 0.1)
				(type default)
			)
			(layer "F.Fab")
		)
		(fp_line
			(start -0.67945 -0.305054)
			(end -0.12065 -0.305054)
			(stroke
				(width 0.1)
				(type default)
			)
			(layer "F.Fab")
		)
		(pad "1" smd circle
			(at -0.40005 0 180)
			(size 0 0)
			(layers "F.Cu" "F.Mask" "F.Paste")
			(net "FPGA_PEX3_MODE_SEL2_ISO")
		)
		(pad "2" smd circle
			(at 0.40005 0 180)
			(size 0 0)
			(layers "F.Cu" "F.Mask" "F.Paste")
			(net "PEX3_MODE_SEL2")
		)
	)
	(footprint ""
		(layer "F.Cu")
		(at 126.221236 -175.007524)
		(property "Reference" "R1084"
			(at 0 0 0)
			(layer "F.SilkS")
			(hide yes)
			(effects
				(font
					(size 1.27 1.27)
				)
			)
		)
		(property "Value" ""
			(at 0 0 0)
			(layer "F.Fab")
			(effects
				(font
					(size 1.27 1.27)
				)
			)
		)
		(duplicate_pad_numbers_are_jumpers no)
		(fp_line
			(start -0.7874 -0.4064)
			(end 0.7874 -0.4064)
			(stroke
				(width 0.1524)
				(type default)
			)
			(layer "F.SilkS")
		)
		(fp_line
			(start -0.67945 -0.305054)
			(end -0.12065 -0.305054)
			(stroke
				(width 0.1)
				(type default)
			)
			(layer "F.Fab")
		)
		(fp_line
			(start -0.67945 0.3048)
			(end -0.67945 -0.305054)
			(stroke
				(width 0.1)
				(type default)
			)
			(layer "F.Fab")
		)
		(fp_line
			(start -0.12065 -0.305054)
			(end -0.12065 -0.2794)
			(stroke
				(width 0.1)
				(type default)
			)
			(layer "F.Fab")
		)
		(fp_line
			(start -0.12065 -0.2794)
			(end 0.12065 -0.2794)
			(stroke
				(width 0.1)
				(type default)
			)
			(layer "F.Fab")
		)
		(fp_line
			(start -0.12065 0.2794)
			(end -0.12065 0.3048)
			(stroke
				(width 0.1)
				(type default)
			)
			(layer "F.Fab")
		)
		(fp_line
			(start -0.12065 0.3048)
			(end -0.67945 0.3048)
			(stroke
				(width 0.1)
				(type default)
			)
			(layer "F.Fab")
		)
		(fp_line
			(start 0.120396 0.2794)
			(end -0.12065 0.2794)
			(stroke
				(width 0.1)
				(type default)
			)
			(layer "F.Fab")
		)
		(fp_line
			(start 0.120396 0.3048)
			(end 0.120396 0.2794)
			(stroke
				(width 0.1)
				(type default)
			)
			(layer "F.Fab")
		)
		(fp_line
			(start 0.12065 -0.3048)
			(end 0.67945 -0.3048)
			(stroke
				(width 0.1)
				(type default)
			)
			(layer "F.Fab")
		)
		(fp_line
			(start 0.12065 -0.2794)
			(end 0.12065 -0.3048)
			(stroke
				(width 0.1)
				(type default)
			)
			(layer "F.Fab")
		)
		(fp_line
			(start 0.67945 -0.3048)
			(end 0.67945 0.3048)
			(stroke
				(width 0.1)
				(type default)
			)
			(layer "F.Fab")
		)
		(fp_line
			(start 0.67945 0.3048)
			(end 0.120396 0.3048)
			(stroke
				(width 0.1)
				(type default)
			)
			(layer "F.Fab")
		)
		(pad "1" smd circle
			(at -0.40005 0)
			(size 0 0)
			(layers "F.Cu" "F.Mask" "F.Paste")
			(net "CLK_100M_DB2000QL_PEX1_S1_R_DP")
		)
		(pad "2" smd circle
			(at 0.40005 0)
			(size 0 0)
			(layers "F.Cu" "F.Mask" "F.Paste")
			(net "CLK_100M_DB2000QL_PEX1_S1_DP")
		)
	)
	(footprint ""
		(layer "F.Cu")
		(at 196.39534 -369.39347)
		(property "Reference" "PR16"
			(at 0 0 0)
			(layer "F.SilkS")
			(hide yes)
			(effects
				(font
					(size 1.27 1.27)
				)
			)
		)
		(property "Value" ""
			(at 0 0 0)
			(layer "F.Fab")
			(effects
				(font
					(size 1.27 1.27)
				)
			)
		)
		(duplicate_pad_numbers_are_jumpers no)
		(fp_line
			(start -0.7874 -0.4064)
			(end 0.7874 -0.4064)
			(stroke
				(width 0.1524)
				(type default)
			)
			(layer "F.SilkS")
		)
		(fp_line
			(start -0.7874 0.4064)
			(end -0.7874 -0.4064)
			(stroke
				(width 0.1524)
				(type default)
			)
			(layer "F.SilkS")
		)
		(fp_line
			(start 0.7874 -0.4064)
			(end 0.7874 0.4064)
			(stroke
				(width 0.1524)
				(type default)
			)
			(layer "F.SilkS")
		)
		(fp_line
			(start 0.7874 0.4064)
			(end -0.7874 0.4064)
			(stroke
				(width 0.1524)
				(type default)
			)
			(layer "F.SilkS")
		)
		(fp_line
			(start -0.67945 -0.305054)
			(end -0.12065 -0.305054)
			(stroke
				(width 0.1)
				(type default)
			)
			(layer "F.Fab")
		)
		(fp_line
			(start -0.67945 0.3048)
			(end -0.67945 -0.305054)
			(stroke
				(width 0.1)
				(type default)
			)
			(layer "F.Fab")
		)
		(fp_line
			(start -0.12065 -0.305054)
			(end -0.12065 -0.2794)
			(stroke
				(width 0.1)
				(type default)
			)
			(layer "F.Fab")
		)
		(fp_line
			(start -0.12065 -0.2794)
			(end 0.12065 -0.2794)
			(stroke
				(width 0.1)
				(type default)
			)
			(layer "F.Fab")
		)
		(fp_line
			(start -0.12065 0.2794)
			(end -0.12065 0.3048)
			(stroke
				(width 0.1)
				(type default)
			)
			(layer "F.Fab")
		)
		(fp_line
			(start -0.12065 0.3048)
			(end -0.67945 0.3048)
			(stroke
				(width 0.1)
				(type default)
			)
			(layer "F.Fab")
		)
		(fp_line
			(start 0.120396 0.2794)
			(end -0.12065 0.2794)
			(stroke
				(width 0.1)
				(type default)
			)
			(layer "F.Fab")
		)
		(fp_line
			(start 0.120396 0.3048)
			(end 0.120396 0.2794)
			(stroke
				(width 0.1)
				(type default)
			)
			(layer "F.Fab")
		)
		(fp_line
			(start 0.12065 -0.3048)
			(end 0.67945 -0.3048)
			(stroke
				(width 0.1)
				(type default)
			)
			(layer "F.Fab")
		)
		(fp_line
			(start 0.12065 -0.2794)
			(end 0.12065 -0.3048)
			(stroke
				(width 0.1)
				(type default)
			)
			(layer "F.Fab")
		)
		(fp_line
			(start 0.67945 -0.3048)
			(end 0.67945 0.3048)
			(stroke
				(width 0.1)
				(type default)
			)
			(layer "F.Fab")
		)
		(fp_line
			(start 0.67945 0.3048)
			(end 0.120396 0.3048)
			(stroke
				(width 0.1)
				(type default)
			)
			(layer "F.Fab")
		)
		(pad "1" smd circle
			(at -0.40005 0)
			(size 0 0)
			(layers "F.Cu" "F.Mask" "F.Paste")
			(net "HSC_VTEMP")
		)
		(pad "2" smd circle
			(at 0.40005 0)
			(size 0 0)
			(layers "F.Cu" "F.Mask" "F.Paste")
			(net "AGND_HSC")
		)
	)
	(footprint ""
		(layer "F.Cu")
		(at 355.913436 -136.328404 180)
		(property "Reference" "PC349"
			(at 0 0 180)
			(layer "F.SilkS")
			(hide yes)
			(effects
				(font
					(size 1.27 1.27)
				)
			)
		)
		(property "Value" ""
			(at 0 0 180)
			(layer "F.Fab")
			(effects
				(font
					(size 1.27 1.27)
				)
			)
		)
		(duplicate_pad_numbers_are_jumpers no)
		(fp_line
			(start 0.7874 0.4064)
			(end -0.7874 0.4064)
			(stroke
				(width 0.1524)
				(type default)
			)
			(layer "F.SilkS")
		)
		(fp_line
			(start 0.7874 -0.4064)
			(end 0.7874 0.4064)
			(stroke
				(width 0.1524)
				(type default)
			)
			(layer "F.SilkS")
		)
		(fp_line
			(start -0.7874 0.4064)
			(end -0.7874 -0.4064)
			(stroke
				(width 0.1524)
				(type default)
			)
			(layer "F.SilkS")
		)
		(fp_line
			(start -0.7874 -0.4064)
			(end 0.7874 -0.4064)
			(stroke
				(width 0.1524)
				(type default)
			)
			(layer "F.SilkS")
		)
		(fp_line
			(start 0.67945 0.3048)
			(end 0.120396 0.3048)
			(stroke
				(width 0.1)
				(type default)
			)
			(layer "F.Fab")
		)
		(fp_line
			(start 0.67945 -0.3048)
			(end 0.67945 0.3048)
			(stroke
				(width 0.1)
				(type default)
			)
			(layer "F.Fab")
		)
		(fp_line
			(start 0.12065 -0.2794)
			(end 0.12065 -0.3048)
			(stroke
				(width 0.1)
				(type default)
			)
			(layer "F.Fab")
		)
		(fp_line
			(start 0.12065 -0.3048)
			(end 0.67945 -0.3048)
			(stroke
				(width 0.1)
				(type default)
			)
			(layer "F.Fab")
		)
		(fp_line
			(start 0.120396 0.3048)
			(end 0.120396 0.2794)
			(stroke
				(width 0.1)
				(type default)
			)
			(layer "F.Fab")
		)
		(fp_line
			(start 0.120396 0.2794)
			(end -0.12065 0.2794)
			(stroke
				(width 0.1)
				(type default)
			)
			(layer "F.Fab")
		)
		(fp_line
			(start -0.12065 0.3048)
			(end -0.67945 0.3048)
			(stroke
				(width 0.1)
				(type default)
			)
			(layer "F.Fab")
		)
		(fp_line
			(start -0.12065 0.2794)
			(end -0.12065 0.3048)
			(stroke
				(width 0.1)
				(type default)
			)
			(layer "F.Fab")
		)
		(fp_line
			(start -0.12065 -0.2794)
			(end 0.12065 -0.2794)
			(stroke
				(width 0.1)
				(type default)
			)
			(layer "F.Fab")
		)
		(fp_line
			(start -0.12065 -0.305054)
			(end -0.12065 -0.2794)
			(stroke
				(width 0.1)
				(type default)
			)
			(layer "F.Fab")
		)
		(fp_line
			(start -0.67945 0.3048)
			(end -0.67945 -0.305054)
			(stroke
				(width 0.1)
				(type default)
			)
			(layer "F.Fab")
		)
		(fp_line
			(start -0.67945 -0.305054)
			(end -0.12065 -0.305054)
			(stroke
				(width 0.1)
				(type default)
			)
			(layer "F.Fab")
		)
		(pad "1" smd circle
			(at -0.40005 0 180)
			(size 0 0)
			(layers "F.Cu" "F.Mask" "F.Paste")
			(net "P5V_AUX")
		)
		(pad "2" smd circle
			(at 0.40005 0 180)
			(size 0 0)
			(layers "F.Cu" "F.Mask" "F.Paste")
			(net "GND")
		)
	)
	(footprint ""
		(layer "F.Cu")
		(at 209.301334 -55.78475 -90)
		(property "Reference" "PD107"
			(at 4.17195 2.137664 90)
			(unlocked yes)
			(layer "F.SilkS")
			(effects
				(font
					(size 0.7874 0.5842)
					(thickness 0.1524)
				)
				(justify left)
			)
		)
		(property "Value" ""
			(at 0 0 270)
			(layer "F.Fab")
			(effects
				(font
					(size 1.27 1.27)
				)
			)
		)
		(duplicate_pad_numbers_are_jumpers no)
		(fp_line
			(start -3.400044 1.459992)
			(end -3.400044 -1.459992)
			(stroke
				(width 0.1524)
				(type default)
			)
			(layer "F.SilkS")
		)
		(fp_line
			(start 4.107942 1.459992)
			(end -3.400044 1.459992)
			(stroke
				(width 0.1524)
				(type default)
			)
			(layer "F.SilkS")
		)
		(fp_line
			(start -3.400044 -1.459992)
			(end 4.107942 -1.459992)
			(stroke
				(width 0.1524)
				(type default)
			)
			(layer "F.SilkS")
		)
		(fp_line
			(start 4.107942 -1.459992)
			(end 4.107942 1.459992)
			(stroke
				(width 0.1524)
				(type default)
			)
			(layer "F.SilkS")
		)
		(fp_poly
			(pts
				(xy 4.107942 -1.459992) (xy 4.107942 1.459992) (xy 3.308096 1.459992) (xy 3.308096 -1.459992)
			)
			(stroke
				(width 0)
				(type default)
			)
			(fill yes)
			(layer "F.SilkS")
		)
		(fp_line
			(start -2.29997 1.459992)
			(end -2.29997 -1.459992)
			(stroke
				(width 0.1)
				(type default)
			)
			(layer "F.Fab")
		)
		(fp_line
			(start 2.29997 1.459992)
			(end -2.29997 1.459992)
			(stroke
				(width 0.1)
				(type default)
			)
			(layer "F.Fab")
		)
		(fp_line
			(start -2.29997 -1.459992)
			(end 2.29997 -1.459992)
			(stroke
				(width 0.1)
				(type default)
			)
			(layer "F.Fab")
		)
		(fp_line
			(start 2.29997 -1.459992)
			(end 2.29997 1.459992)
			(stroke
				(width 0.1)
				(type default)
			)
			(layer "F.Fab")
		)
		(fp_text user "-"
			(at 5.4102 0.29845 90)
			(unlocked yes)
			(layer "F.SilkS")
			(effects
				(font
					(size 1.905 1.4224)
					(thickness 0.1524)
				)
				(justify left)
			)
		)
		(fp_text user "+"
			(at -4.7752 -0.12065 270)
			(unlocked yes)
			(layer "F.SilkS")
			(effects
				(font
					(size 1.905 1.4224)
					(thickness 0.1524)
				)
				(justify left)
			)
		)
		(fp_text user "-"
			(at 5.4102 0.29845 90)
			(unlocked yes)
			(layer "F.Fab")
			(effects
				(font
					(size 1.905 1.4224)
					(thickness 0.1524)
				)
				(justify left)
			)
		)
		(fp_text user "+"
			(at -4.7752 -0.12065 270)
			(unlocked yes)
			(layer "F.Fab")
			(effects
				(font
					(size 1.905 1.4224)
					(thickness 0.1524)
				)
				(justify left)
			)
		)
		(pad "A" smd rect
			(at -1.999996 0)
			(size 1.7018 2.5146)
			(layers "F.Cu" "F.Mask" "F.Paste")
			(net "GND")
		)
		(pad "C" smd rect
			(at 1.999996 0)
			(size 1.7018 2.5146)
			(layers "F.Cu" "F.Mask" "F.Paste")
			(net "P12V_SSD7_R")
		)
	)
)
